FILE_TYPE = CONNECTIVITY;
{Allegro Design Entry HDL 17.4-2019 S026 (4007227) 1/17/2022}
"PAGE_NUMBER" = 48;
0"NC";
1"M_L_CPU1_SA_DQ<31:0>";
2"M_L_CPU1_SB_DQ<31:0>";
3"M_L_CPU1_SA_CB<7:0>";
4"M_L_CPU1_SB_CB<7:0>";
5"M_L_CPU1_SA_DQS_DN<9:0>";
6"M_L_CPU1_SA_DQS_DP<9:0>";
7"M_L_CPU1_SB_DQS_DP<9:0>";
8"M_L_CPU1_SB_DQS_DN<9:0>";
9"M_L_CPU1_SB_CA<6:0>";
10"M_L_CPU1_SA_CA<6:0>";
11"M_L_CPU1_ALERT_N";
12"M_L_CPU1_ALERT_R_N";
13"TP_M_L_CPU1_SA_TEST39L";
14"M_L_CPU1_CLK_DP<0>";
15"M_L_CPU1_CLK_DN<0>";
16"M_L_CPU1_SA_CS_N<0>";
17"M_L_CPU1_SA_CS_N<1>";
18"M_L_CPU1_SA_RSP<0>";
19"M_L_CPU1_SA_PAR";
20"M_L_CPU1_SB_CS_N<1>";
21"M_L_CPU1_SB_CS_N<0>";
22"M_L_CPU1_SB_PAR";
23"M_L_CPU1_SB_RSP<0>";
24"M_L_CPU1_RESET_N";
25"M_L_CPU1_SA_CA<1>";
26"M_L_CPU1_SB_CA<0>";
27"M_L_CPU1_SB_DQS_DN<8>";
28"M_L_CPU1_SA_CA<0>";
29"M_L_CPU1_SB_CA<6>";
30"M_L_CPU1_SA_CA<6>";
31"M_L_CPU1_SB_CA<5>";
32"M_L_CPU1_SB_DQS_DP<9>";
33"M_L_CPU1_SA_CA<5>";
34"M_L_CPU1_SB_CA<4>";
35"M_L_CPU1_SB_DQS_DP<8>";
36"M_L_CPU1_SA_CA<4>";
37"M_L_CPU1_SB_CA<3>";
38"M_L_CPU1_SA_CA<3>";
39"M_L_CPU1_SB_CA<2>";
40"M_L_CPU1_SA_CA<2>";
41"M_L_CPU1_SB_CA<1>";
42"M_L_CPU1_SB_DQS_DN<9>";
43"M_L_CPU1_SB_DQS_DP<4>";
44"M_L_CPU1_SA_DQS_DP<9>";
45"M_L_CPU1_SB_DQS_DP<3>";
46"M_L_CPU1_SB_DQS_DN<7>";
47"M_L_CPU1_SB_DQS_DP<2>";
48"M_L_CPU1_SB_DQS_DN<6>";
49"M_L_CPU1_SB_DQS_DP<1>";
50"M_L_CPU1_SB_DQS_DN<5>";
51"M_L_CPU1_SB_DQS_DP<0>";
52"M_L_CPU1_SB_DQS_DN<4>";
53"M_L_CPU1_SA_DQS_DN<9>";
54"M_L_CPU1_SB_DQS_DN<3>";
55"M_L_CPU1_SA_DQS_DN<8>";
56"M_L_CPU1_SB_DQS_DN<2>";
57"M_L_CPU1_SB_DQS_DN<1>";
58"M_L_CPU1_SB_DQS_DN<0>";
59"M_L_CPU1_SB_DQS_DP<7>";
60"M_L_CPU1_SB_DQS_DP<6>";
61"M_L_CPU1_SB_DQS_DP<5>";
62"M_L_CPU1_SA_DQS_DP<8>";
63"M_L_CPU1_SA_DQS_DP<7>";
64"M_L_CPU1_SA_DQS_DP<6>";
65"M_L_CPU1_SA_DQS_DP<5>";
66"M_L_CPU1_SA_DQS_DP<4>";
67"M_L_CPU1_SA_DQS_DP<3>";
68"M_L_CPU1_SA_DQS_DN<7>";
69"M_L_CPU1_SA_DQS_DP<2>";
70"M_L_CPU1_SA_DQS_DN<6>";
71"M_L_CPU1_SA_DQS_DP<1>";
72"M_L_CPU1_SA_DQS_DN<5>";
73"M_L_CPU1_SA_DQS_DP<0>";
74"M_L_CPU1_SA_DQS_DN<4>";
75"M_L_CPU1_SA_DQS_DN<3>";
76"M_L_CPU1_SA_DQS_DN<2>";
77"M_L_CPU1_SA_DQS_DN<1>";
78"M_L_CPU1_SA_DQS_DN<0>";
79"M_L_CPU1_SB_CB<7>";
80"M_L_CPU1_SB_CB<6>";
81"M_L_CPU1_SB_CB<5>";
82"M_L_CPU1_SB_CB<4>";
83"M_L_CPU1_SB_CB<3>";
84"M_L_CPU1_SB_CB<2>";
85"M_L_CPU1_SA_CB<7>";
86"M_L_CPU1_SB_CB<1>";
87"M_L_CPU1_SA_CB<6>";
88"M_L_CPU1_SB_CB<0>";
89"M_L_CPU1_SA_CB<1>";
90"M_L_CPU1_SA_CB<0>";
91"M_L_CPU1_SB_DQ<29>";
92"M_L_CPU1_SB_DQ<28>";
93"M_L_CPU1_SB_DQ<27>";
94"M_L_CPU1_SB_DQ<26>";
95"M_L_CPU1_SB_DQ<25>";
96"M_L_CPU1_SB_DQ<24>";
97"M_L_CPU1_SB_DQ<23>";
98"M_L_CPU1_SB_DQ<22>";
99"M_L_CPU1_SB_DQ<21>";
100"M_L_CPU1_SB_DQ<20>";
101"M_L_CPU1_SB_DQ<31>";
102"M_L_CPU1_SA_CB<5>";
103"M_L_CPU1_SB_DQ<30>";
104"M_L_CPU1_SA_CB<4>";
105"M_L_CPU1_SA_CB<3>";
106"M_L_CPU1_SA_CB<2>";
107"M_L_CPU1_SB_DQ<3>";
108"M_L_CPU1_SB_DQ<2>";
109"M_L_CPU1_SB_DQ<1>";
110"M_L_CPU1_SB_DQ<19>";
111"M_L_CPU1_SB_DQ<18>";
112"M_L_CPU1_SB_DQ<17>";
113"M_L_CPU1_SB_DQ<16>";
114"M_L_CPU1_SB_DQ<15>";
115"M_L_CPU1_SB_DQ<14>";
116"M_L_CPU1_SB_DQ<13>";
117"M_L_CPU1_SB_DQ<12>";
118"M_L_CPU1_SB_DQ<11>";
119"M_L_CPU1_SB_DQ<9>";
120"M_L_CPU1_SB_DQ<10>";
121"M_L_CPU1_SB_DQ<8>";
122"M_L_CPU1_SB_DQ<7>";
123"M_L_CPU1_SB_DQ<6>";
124"M_L_CPU1_SB_DQ<5>";
125"M_L_CPU1_SB_DQ<4>";
126"M_L_CPU1_SA_DQ<21>";
127"M_L_CPU1_SA_DQ<20>";
128"M_L_CPU1_SA_DQ<31>";
129"M_L_CPU1_SA_DQ<30>";
130"M_L_CPU1_SB_DQ<0>";
131"M_L_CPU1_SA_DQ<19>";
132"M_L_CPU1_SA_DQ<18>";
133"M_L_CPU1_SA_DQ<29>";
134"M_L_CPU1_SA_DQ<17>";
135"M_L_CPU1_SA_DQ<28>";
136"M_L_CPU1_SA_DQ<16>";
137"M_L_CPU1_SA_DQ<27>";
138"M_L_CPU1_SA_DQ<26>";
139"M_L_CPU1_SA_DQ<25>";
140"M_L_CPU1_SA_DQ<24>";
141"M_L_CPU1_SA_DQ<23>";
142"M_L_CPU1_SA_DQ<22>";
143"M_L_CPU1_SA_DQ<4>";
144"M_L_CPU1_SA_DQ<10>";
145"M_L_CPU1_SA_DQ<3>";
146"M_L_CPU1_SA_DQ<2>";
147"M_L_CPU1_SA_DQ<1>";
148"M_L_CPU1_SA_DQ<0>";
149"M_L_CPU1_SA_DQ<9>";
150"M_L_CPU1_SA_DQ<15>";
151"M_L_CPU1_SA_DQ<8>";
152"M_L_CPU1_SA_DQ<14>";
153"M_L_CPU1_SA_DQ<7>";
154"M_L_CPU1_SA_DQ<13>";
155"M_L_CPU1_SA_DQ<6>";
156"M_L_CPU1_SA_DQ<12>";
157"M_L_CPU1_SA_DQ<5>";
158"M_L_CPU1_SA_DQ<11>";
%"GENOA_SP5"
"35","(-4550,3550)","0","pure_quanta","I159";
;
LOCATION"U26"
$SEC"35"
CDS_SEC"35"
PART_TYPE"SMLF"
MATERIAL"IO"
VALUE"SOCKET6096_13568-001"
CDS_LIB"pure_quanta"
CDS_LMAN_SYM_OUTLINE"-650,2525,650,-2525"
NEEDS_NO_SIZE"TRUE"
PART_NUMBER"DGA^6000030";
"TEST39L"
$PN"BF11"13;
"MLA_CA1"
$PN"AY9"25;
"MLA_CHECK1"
$PN"AK11"89;
"MLA_DATA4"
$PN"J9"143;
"MLA_DATA10"
$PN"M9"144;
"MLA_DATA21"
$PN"AB11"126;
"MLB_CA0"
$PN"BG10"26;
"MLB_DATA3"
$PN"CD11"107;
"MLB_DQS_H4"
$PN"BY11"43;
"MLB_DQS_L8"
$PN"DC10"27;
"MLA_CA0"
$PN"AW9"28;
"MLA_CHECK0"
$PN"AJ9"90;
"MLA_DATA3"
$PN"G10"145;
"MLA_DATA20"
$PN"AA9"127;
"MLA_DATA31"
$PN"AJ10"128;
"MLA_DQS_H9"
$PN"AN10"44;
"MLB_DATA2"
$PN"CC9"108;
"MLB_DQS_H3"
$PN"DB9"45;
"MLB_DQS_L7"
$PN"CU10"46;
"MLA1_CS_L1"
$PN"AW10"0;
"MLA_DATA2"
$PN"F9"146;
"MLA_DATA30"
$PN"AH9"129;
"MLA_DQS_H8"
$PN"AG10"62;
"MLB_DATA1"
$PN"CC10"109;
"MLB_DATA19"
$PN"CT11"110;
"MLB_DQS_H2"
$PN"CT9"47;
"MLB_DQS_L6"
$PN"CL10"48;
"MLA0_CS_L1"
$PN"AV11"17;
"MLA1_CS_L0"
$PN"AV9"0;
"MLA_DATA1"
$PN"F11"147;
"MLA_DQS_H7"
$PN"AA10"63;
"MLB_DATA0"
$PN"CB9"130;
"MLB_DATA18"
$PN"CR9"111;
"MLB_DATA29"
$PN"DE10"91;
"MLB_DQS_H1"
$PN"CK9"49;
"MLB_DQS_L5"
$PN"CE10"50;
"ML1_CLK_L"
$PN"BG9"0;
"MLA0_CS_L0"
$PN"AU9"16;
"MLA_DATA0"
$PN"E9"148;
"MLA_DQS_H6"
$PN"R10"64;
"MLB_DATA17"
$PN"CR10"112;
"MLB_DATA28"
$PN"DD9"92;
"MLB_DQS_H0"
$PN"CD9"51;
"MLB_DQS_L4"
$PN"BW10"52;
"MLB_PAR"
$PN"BL10"22;
"ML0_CLK_L"
$PN"BD9"15;
"MLA_DQS_H5"
$PN"J10"65;
"MLA_DQS_L9"
$PN"AM11"53;
"MLA_PAR"
$PN"BC10"19;
"MLB1_RSP_L"
$PN"BR9"0;
"MLB_CHECK7"
$PN"BV11"79;
"MLB_DATA16"
$PN"CP9"113;
"MLB_DATA27"
$PN"DB11"93;
"MLB_DQS_L3"
$PN"DC9"54;
"MLA_DQS_H4"
$PN"AL9"66;
"MLA_DQS_L8"
$PN"AF11"55;
"MLB0_RSP_L"
$PN"BP9"23;
"MLB_CHECK6"
$PN"BU9"80;
"MLB_DATA15"
$PN"CP11"114;
"MLB_DATA26"
$PN"DA9"94;
"MLB_DQS_L2"
$PN"CU9"56;
"MLA_DQS_H3"
$PN"AE9"67;
"MLA_DQS_L7"
$PN"Y11"68;
"MLB_CHECK5"
$PN"BU10"81;
"MLB_DATA14"
$PN"CN9"115;
"MLB_DATA25"
$PN"DA10"95;
"MLB_DQS_L1"
$PN"CL9"57;
"ML1_CLK_H"
$PN"BF9"0;
"MLA_DATA19"
$PN"W10"131;
"MLA_DQS_H2"
$PN"W9"69;
"MLA_DQS_L6"
$PN"P11"70;
"MLB_CHECK4"
$PN"BT9"82;
"MLB_DATA13"
$PN"CN10"116;
"MLB_DATA24"
$PN"CY9"96;
"MLB_DQS_L0"
$PN"CE9"58;
"ML0_CLK_H"
$PN"BC9"14;
"MLA_DATA18"
$PN"V9"132;
"MLA_DATA29"
$PN"AH11"133;
"MLA_DQS_H1"
$PN"N9"71;
"MLA_DQS_L5"
$PN"H11"72;
"MLB_CHECK3"
$PN"CB11"83;
"MLB_DATA12"
$PN"CM9"117;
"MLB_DATA23"
$PN"CY11"97;
"MLA_DATA17"
$PN"V11"134;
"MLA_DATA28"
$PN"AG9"135;
"MLA_DQS_H0"
$PN"G9"73;
"MLA_DQS_L4"
$PN"AM9"74;
"MLB_CHECK2"
$PN"CA9"84;
"MLB_DATA11"
$PN"CK11"118;
"MLB_DATA22"
$PN"CW9"98;
"ML_ALERT_L"
$PN"AT11"12;
"MLA1_RSP_L"
$PN"BP11"0;
"MLA_CHECK7"
$PN"AR10"85;
"MLA_DATA16"
$PN"U9"136;
"MLA_DATA27"
$PN"AE10"137;
"MLA_DQS_L3"
$PN"AF9"75;
"MLB_CA6"
$PN"BK9"29;
"MLB_CHECK1"
$PN"CA10"86;
"MLB_DATA9"
$PN"CJ10"119;
"MLB_DATA10"
$PN"CJ9"120;
"MLB_DATA21"
$PN"CW10"99;
"MLA0_RSP_L"
$PN"BN10"18;
"MLA_CA6"
$PN"BB11"30;
"MLA_CHECK6"
$PN"AP9"87;
"MLA_DATA9"
$PN"M11"149;
"MLA_DATA15"
$PN"U10"150;
"MLA_DATA26"
$PN"AD9"138;
"MLA_DQS_L2"
$PN"Y9"76;
"MLB_CA5"
$PN"BK11"31;
"MLB_CHECK0"
$PN"BY9"88;
"MLB_DATA8"
$PN"CH9"121;
"MLB_DATA20"
$PN"CV9"100;
"MLB_DATA31"
$PN"DF9"101;
"MLB_DQS_H9"
$PN"BV9"32;
"MLA_CA5"
$PN"BB9"33;
"MLA_CHECK5"
$PN"AP11"102;
"MLA_DATA8"
$PN"L9"151;
"MLA_DATA14"
$PN"T9"152;
"MLA_DATA25"
$PN"AD11"139;
"MLA_DQS_L1"
$PN"P9"77;
"MLB1_CS_L1"
$PN"BM9"0;
"MLB_CA4"
$PN"BJ10"34;
"MLB_DATA7"
$PN"CH11"122;
"MLB_DATA30"
$PN"DE9"103;
"MLB_DQS_H8"
$PN"DD11"35;
"MLA_CA4"
$PN"BA9"36;
"MLA_CHECK4"
$PN"AN9"104;
"MLA_DATA7"
$PN"L10"153;
"MLA_DATA13"
$PN"T11"154;
"MLA_DATA24"
$PN"AC9"140;
"MLA_DQS_L0"
$PN"H9"78;
"MLB0_CS_L1"
$PN"BN9"20;
"MLB1_CS_L0"
$PN"BL9"0;
"MLB_CA3"
$PN"BJ9"37;
"MLB_DATA6"
$PN"CG9"123;
"MLB_DQS_H7"
$PN"CV11"59;
"MLA_CA3"
$PN"BA10"38;
"MLA_CHECK3"
$PN"AL10"105;
"MLA_DATA6"
$PN"K9"155;
"MLA_DATA12"
$PN"R9"156;
"MLA_DATA23"
$PN"AC10"141;
"MLB0_CS_L0"
$PN"BM11"21;
"MLB_CA2"
$PN"BH9"39;
"MLB_DATA5"
$PN"CG10"124;
"MLB_DQS_H6"
$PN"CM11"60;
"ML_RESET_L"
$PN"AU10"24;
"MLA_CA2"
$PN"AY11"40;
"MLA_CHECK2"
$PN"AK9"106;
"MLA_DATA5"
$PN"K11"157;
"MLA_DATA11"
$PN"N10"158;
"MLA_DATA22"
$PN"AB9"142;
"MLB_CA1"
$PN"BH11"41;
"MLB_DATA4"
$PN"CF9"125;
"MLB_DQS_H5"
$PN"CF11"61;
"MLB_DQS_L9"
$PN"BW9"42;
%"TAP"
"1","(-3275,5925)","0","mstr_standard","I162";
;
CDS_LIB"mstr_standard"
BODY_TYPE"PLUMBING"
HDL_TAP"TRUE";
"B \NAC \NWC"1;
"S \NAC"
BN"0"148;
%"TAP"
"1","(-3275,5775)","0","mstr_standard","I163";
;
CDS_LIB"mstr_standard"
BODY_TYPE"PLUMBING"
HDL_TAP"TRUE";
"B \NAC \NWC"1;
"S \NAC"
BN"3"145;
%"TAP"
"1","(-3275,5825)","0","mstr_standard","I164";
;
CDS_LIB"mstr_standard"
BODY_TYPE"PLUMBING"
HDL_TAP"TRUE";
"B \NAC \NWC"1;
"S \NAC"
BN"2"146;
%"TAP"
"1","(-3275,5875)","0","mstr_standard","I165";
;
CDS_LIB"mstr_standard"
BODY_TYPE"PLUMBING"
HDL_TAP"TRUE";
"B \NAC \NWC"1;
"S \NAC"
BN"1"147;
%"TAP"
"1","(-3275,5725)","0","mstr_standard","I166";
;
CDS_LIB"mstr_standard"
BODY_TYPE"PLUMBING"
HDL_TAP"TRUE";
"B \NAC \NWC"1;
"S \NAC"
BN"4"143;
%"TAP"
"1","(-3275,5675)","0","mstr_standard","I167";
;
CDS_LIB"mstr_standard"
BODY_TYPE"PLUMBING"
HDL_TAP"TRUE";
"B \NAC \NWC"1;
"S \NAC"
BN"5"157;
%"TAP"
"1","(-3275,5575)","0","mstr_standard","I168";
;
CDS_LIB"mstr_standard"
BODY_TYPE"PLUMBING"
HDL_TAP"TRUE";
"B \NAC \NWC"1;
"S \NAC"
BN"7"153;
%"TAP"
"1","(-3275,5625)","0","mstr_standard","I169";
;
CDS_LIB"mstr_standard"
BODY_TYPE"PLUMBING"
HDL_TAP"TRUE";
"B \NAC \NWC"1;
"S \NAC"
BN"6"155;
%"TAP"
"1","(-3275,5425)","0","mstr_standard","I170";
;
CDS_LIB"mstr_standard"
BODY_TYPE"PLUMBING"
HDL_TAP"TRUE";
"B \NAC \NWC"1;
"S \NAC"
BN"9"149;
%"TAP"
"1","(-3275,5475)","0","mstr_standard","I171";
;
CDS_LIB"mstr_standard"
BODY_TYPE"PLUMBING"
HDL_TAP"TRUE";
"B \NAC \NWC"1;
"S \NAC"
BN"8"151;
%"TAP"
"1","(-3275,5375)","0","mstr_standard","I172";
;
CDS_LIB"mstr_standard"
BODY_TYPE"PLUMBING"
HDL_TAP"TRUE";
"B \NAC \NWC"1;
"S \NAC"
BN"10"144;
%"TAP"
"1","(-3275,5325)","0","mstr_standard","I173";
;
CDS_LIB"mstr_standard"
BODY_TYPE"PLUMBING"
HDL_TAP"TRUE";
"B \NAC \NWC"1;
"S \NAC"
BN"11"158;
%"TAP"
"1","(-3275,5275)","0","mstr_standard","I174";
;
CDS_LIB"mstr_standard"
BODY_TYPE"PLUMBING"
HDL_TAP"TRUE";
"B \NAC \NWC"1;
"S \NAC"
BN"12"156;
%"TAP"
"1","(-3275,5225)","0","mstr_standard","I175";
;
CDS_LIB"mstr_standard"
BODY_TYPE"PLUMBING"
HDL_TAP"TRUE";
"B \NAC \NWC"1;
"S \NAC"
BN"13"154;
%"TAP"
"1","(-3275,5125)","0","mstr_standard","I176";
;
CDS_LIB"mstr_standard"
BODY_TYPE"PLUMBING"
HDL_TAP"TRUE";
"B \NAC \NWC"1;
"S \NAC"
BN"15"150;
%"TAP"
"1","(-3275,5175)","0","mstr_standard","I177";
;
CDS_LIB"mstr_standard"
BODY_TYPE"PLUMBING"
HDL_TAP"TRUE";
"B \NAC \NWC"1;
"S \NAC"
BN"14"152;
%"TAP"
"1","(-3275,5025)","0","mstr_standard","I178";
;
CDS_LIB"mstr_standard"
BODY_TYPE"PLUMBING"
HDL_TAP"TRUE";
"B \NAC \NWC"1;
"S \NAC"
BN"16"136;
%"TAP"
"1","(-3275,4875)","0","mstr_standard","I179";
;
CDS_LIB"mstr_standard"
BODY_TYPE"PLUMBING"
HDL_TAP"TRUE";
"B \NAC \NWC"1;
"S \NAC"
BN"19"131;
%"TAP"
"1","(-3275,4925)","0","mstr_standard","I180";
;
CDS_LIB"mstr_standard"
BODY_TYPE"PLUMBING"
HDL_TAP"TRUE";
"B \NAC \NWC"1;
"S \NAC"
BN"18"132;
%"TAP"
"1","(-3275,4975)","0","mstr_standard","I181";
;
CDS_LIB"mstr_standard"
BODY_TYPE"PLUMBING"
HDL_TAP"TRUE";
"B \NAC \NWC"1;
"S \NAC"
BN"17"134;
%"TAP"
"1","(-3275,4825)","0","mstr_standard","I182";
;
CDS_LIB"mstr_standard"
BODY_TYPE"PLUMBING"
HDL_TAP"TRUE";
"B \NAC \NWC"1;
"S \NAC"
BN"20"127;
%"TAP"
"1","(-3275,4775)","0","mstr_standard","I183";
;
CDS_LIB"mstr_standard"
BODY_TYPE"PLUMBING"
HDL_TAP"TRUE";
"B \NAC \NWC"1;
"S \NAC"
BN"21"126;
%"TAP"
"1","(-3275,4675)","0","mstr_standard","I184";
;
CDS_LIB"mstr_standard"
BODY_TYPE"PLUMBING"
HDL_TAP"TRUE";
"B \NAC \NWC"1;
"S \NAC"
BN"23"141;
%"TAP"
"1","(-3275,4725)","0","mstr_standard","I185";
;
CDS_LIB"mstr_standard"
BODY_TYPE"PLUMBING"
HDL_TAP"TRUE";
"B \NAC \NWC"1;
"S \NAC"
BN"22"142;
%"TAP"
"1","(-3275,4525)","0","mstr_standard","I186";
;
CDS_LIB"mstr_standard"
BODY_TYPE"PLUMBING"
HDL_TAP"TRUE";
"B \NAC \NWC"1;
"S \NAC"
BN"25"139;
%"TAP"
"1","(-3275,4575)","0","mstr_standard","I187";
;
CDS_LIB"mstr_standard"
BODY_TYPE"PLUMBING"
HDL_TAP"TRUE";
"B \NAC \NWC"1;
"S \NAC"
BN"24"140;
%"TAP"
"1","(-3275,4375)","0","mstr_standard","I188";
;
CDS_LIB"mstr_standard"
BODY_TYPE"PLUMBING"
HDL_TAP"TRUE";
"B \NAC \NWC"1;
"S \NAC"
BN"28"135;
%"TAP"
"1","(-3275,4425)","0","mstr_standard","I189";
;
CDS_LIB"mstr_standard"
BODY_TYPE"PLUMBING"
HDL_TAP"TRUE";
"B \NAC \NWC"1;
"S \NAC"
BN"27"137;
%"TAP"
"1","(-3275,4475)","0","mstr_standard","I190";
;
CDS_LIB"mstr_standard"
BODY_TYPE"PLUMBING"
HDL_TAP"TRUE";
"B \NAC \NWC"1;
"S \NAC"
BN"26"138;
%"TAP"
"1","(-3275,4325)","0","mstr_standard","I191";
;
CDS_LIB"mstr_standard"
BODY_TYPE"PLUMBING"
HDL_TAP"TRUE";
"B \NAC \NWC"1;
"S \NAC"
BN"29"133;
%"TAP"
"1","(-3275,4225)","0","mstr_standard","I192";
;
CDS_LIB"mstr_standard"
BODY_TYPE"PLUMBING"
HDL_TAP"TRUE";
"B \NAC \NWC"1;
"S \NAC"
BN"31"128;
%"TAP"
"1","(-3275,4275)","0","mstr_standard","I193";
;
CDS_LIB"mstr_standard"
BODY_TYPE"PLUMBING"
HDL_TAP"TRUE";
"B \NAC \NWC"1;
"S \NAC"
BN"30"129;
%"TAP"
"1","(-3275,4125)","0","mstr_standard","I194";
;
CDS_LIB"mstr_standard"
BODY_TYPE"PLUMBING"
HDL_TAP"TRUE";
"B \NAC \NWC"2;
"S \NAC"
BN"0"130;
%"TAP"
"1","(-3275,3975)","0","mstr_standard","I196";
;
CDS_LIB"mstr_standard"
BODY_TYPE"PLUMBING"
HDL_TAP"TRUE";
"B \NAC \NWC"2;
"S \NAC"
BN"3"107;
%"TAP"
"1","(-3275,4075)","0","mstr_standard","I197";
;
CDS_LIB"mstr_standard"
BODY_TYPE"PLUMBING"
HDL_TAP"TRUE";
"B \NAC \NWC"2;
"S \NAC"
BN"1"109;
%"TAP"
"1","(-3275,4025)","0","mstr_standard","I198";
;
CDS_LIB"mstr_standard"
BODY_TYPE"PLUMBING"
HDL_TAP"TRUE";
"B \NAC \NWC"2;
"S \NAC"
BN"2"108;
%"TAP"
"1","(-3275,3875)","0","mstr_standard","I199";
;
CDS_LIB"mstr_standard"
BODY_TYPE"PLUMBING"
HDL_TAP"TRUE";
"B \NAC \NWC"2;
"S \NAC"
BN"5"124;
%"TAP"
"1","(-3275,3925)","0","mstr_standard","I200";
;
CDS_LIB"mstr_standard"
BODY_TYPE"PLUMBING"
HDL_TAP"TRUE";
"B \NAC \NWC"2;
"S \NAC"
BN"4"125;
%"TAP"
"1","(-3275,3775)","0","mstr_standard","I201";
;
CDS_LIB"mstr_standard"
BODY_TYPE"PLUMBING"
HDL_TAP"TRUE";
"B \NAC \NWC"2;
"S \NAC"
BN"7"122;
%"TAP"
"1","(-3275,3825)","0","mstr_standard","I202";
;
CDS_LIB"mstr_standard"
BODY_TYPE"PLUMBING"
HDL_TAP"TRUE";
"B \NAC \NWC"2;
"S \NAC"
BN"6"123;
%"TAP"
"1","(-3275,3625)","0","mstr_standard","I203";
;
CDS_LIB"mstr_standard"
BODY_TYPE"PLUMBING"
HDL_TAP"TRUE";
"B \NAC \NWC"2;
"S \NAC"
BN"9"119;
%"TAP"
"1","(-3275,3675)","0","mstr_standard","I204";
;
CDS_LIB"mstr_standard"
BODY_TYPE"PLUMBING"
HDL_TAP"TRUE";
"B \NAC \NWC"2;
"S \NAC"
BN"8"121;
%"TAP"
"1","(-3275,3475)","0","mstr_standard","I205";
;
CDS_LIB"mstr_standard"
BODY_TYPE"PLUMBING"
HDL_TAP"TRUE";
"B \NAC \NWC"2;
"S \NAC"
BN"12"117;
%"TAP"
"1","(-3275,3575)","0","mstr_standard","I206";
;
CDS_LIB"mstr_standard"
BODY_TYPE"PLUMBING"
HDL_TAP"TRUE";
"B \NAC \NWC"2;
"S \NAC"
BN"10"120;
%"TAP"
"1","(-3275,3525)","0","mstr_standard","I207";
;
CDS_LIB"mstr_standard"
BODY_TYPE"PLUMBING"
HDL_TAP"TRUE";
"B \NAC \NWC"2;
"S \NAC"
BN"11"118;
%"TAP"
"1","(-3275,3375)","0","mstr_standard","I208";
;
CDS_LIB"mstr_standard"
BODY_TYPE"PLUMBING"
HDL_TAP"TRUE";
"B \NAC \NWC"2;
"S \NAC"
BN"14"115;
%"TAP"
"1","(-3275,3425)","0","mstr_standard","I209";
;
CDS_LIB"mstr_standard"
BODY_TYPE"PLUMBING"
HDL_TAP"TRUE";
"B \NAC \NWC"2;
"S \NAC"
BN"13"116;
%"TAP"
"1","(-3275,3225)","0","mstr_standard","I210";
;
CDS_LIB"mstr_standard"
BODY_TYPE"PLUMBING"
HDL_TAP"TRUE";
"B \NAC \NWC"2;
"S \NAC"
BN"16"113;
%"TAP"
"1","(-3275,3325)","0","mstr_standard","I211";
;
CDS_LIB"mstr_standard"
BODY_TYPE"PLUMBING"
HDL_TAP"TRUE";
"B \NAC \NWC"2;
"S \NAC"
BN"15"114;
%"TAP"
"1","(-3275,3175)","0","mstr_standard","I212";
;
CDS_LIB"mstr_standard"
BODY_TYPE"PLUMBING"
HDL_TAP"TRUE";
"B \NAC \NWC"2;
"S \NAC"
BN"17"112;
%"TAP"
"1","(-3275,3125)","0","mstr_standard","I213";
;
CDS_LIB"mstr_standard"
BODY_TYPE"PLUMBING"
HDL_TAP"TRUE";
"B \NAC \NWC"2;
"S \NAC"
BN"18"111;
%"TAP"
"1","(-3275,3075)","0","mstr_standard","I214";
;
CDS_LIB"mstr_standard"
BODY_TYPE"PLUMBING"
HDL_TAP"TRUE";
"B \NAC \NWC"2;
"S \NAC"
BN"19"110;
%"TAP"
"1","(-3275,2975)","0","mstr_standard","I215";
;
CDS_LIB"mstr_standard"
BODY_TYPE"PLUMBING"
HDL_TAP"TRUE";
"B \NAC \NWC"2;
"S \NAC"
BN"21"99;
%"TAP"
"1","(-3275,3025)","0","mstr_standard","I216";
;
CDS_LIB"mstr_standard"
BODY_TYPE"PLUMBING"
HDL_TAP"TRUE";
"B \NAC \NWC"2;
"S \NAC"
BN"20"100;
%"TAP"
"1","(-3275,2925)","0","mstr_standard","I217";
;
CDS_LIB"mstr_standard"
BODY_TYPE"PLUMBING"
HDL_TAP"TRUE";
"B \NAC \NWC"2;
"S \NAC"
BN"22"98;
%"TAP"
"1","(-3275,2875)","0","mstr_standard","I218";
;
CDS_LIB"mstr_standard"
BODY_TYPE"PLUMBING"
HDL_TAP"TRUE";
"B \NAC \NWC"2;
"S \NAC"
BN"23"97;
%"TAP"
"1","(-3275,2725)","0","mstr_standard","I219";
;
CDS_LIB"mstr_standard"
BODY_TYPE"PLUMBING"
HDL_TAP"TRUE";
"B \NAC \NWC"2;
"S \NAC"
BN"25"95;
%"TAP"
"1","(-3275,2775)","0","mstr_standard","I220";
;
CDS_LIB"mstr_standard"
BODY_TYPE"PLUMBING"
HDL_TAP"TRUE";
"B \NAC \NWC"2;
"S \NAC"
BN"24"96;
%"TAP"
"1","(-3275,2675)","0","mstr_standard","I221";
;
CDS_LIB"mstr_standard"
BODY_TYPE"PLUMBING"
HDL_TAP"TRUE";
"B \NAC \NWC"2;
"S \NAC"
BN"26"94;
%"TAP"
"1","(-3275,2625)","0","mstr_standard","I222";
;
CDS_LIB"mstr_standard"
BODY_TYPE"PLUMBING"
HDL_TAP"TRUE";
"B \NAC \NWC"2;
"S \NAC"
BN"27"93;
%"TAP"
"1","(-3275,2575)","0","mstr_standard","I223";
;
CDS_LIB"mstr_standard"
BODY_TYPE"PLUMBING"
HDL_TAP"TRUE";
"B \NAC \NWC"2;
"S \NAC"
BN"28"92;
%"TAP"
"1","(-3275,2475)","0","mstr_standard","I224";
;
CDS_LIB"mstr_standard"
BODY_TYPE"PLUMBING"
HDL_TAP"TRUE";
"B \NAC \NWC"2;
"S \NAC"
BN"30"103;
%"TAP"
"1","(-3275,2525)","0","mstr_standard","I225";
;
CDS_LIB"mstr_standard"
BODY_TYPE"PLUMBING"
HDL_TAP"TRUE";
"B \NAC \NWC"2;
"S \NAC"
BN"29"91;
%"TAP"
"1","(-3275,2425)","0","mstr_standard","I226";
;
CDS_LIB"mstr_standard"
BODY_TYPE"PLUMBING"
HDL_TAP"TRUE";
"B \NAC \NWC"2;
"S \NAC"
BN"31"101;
%"TAP"
"1","(-3275,2325)","0","mstr_standard","I227";
;
CDS_LIB"mstr_standard"
BODY_TYPE"PLUMBING"
HDL_TAP"TRUE";
"B \NAC \NWC"3;
"S \NAC"
BN"0"90;
%"TAP"
"1","(-3275,2275)","0","mstr_standard","I228";
;
CDS_LIB"mstr_standard"
BODY_TYPE"PLUMBING"
HDL_TAP"TRUE";
"B \NAC \NWC"3;
"S \NAC"
BN"1"89;
%"TAP"
"1","(-3275,2225)","0","mstr_standard","I229";
;
CDS_LIB"mstr_standard"
BODY_TYPE"PLUMBING"
HDL_TAP"TRUE";
"B \NAC \NWC"3;
"S \NAC"
BN"2"106;
%"TAP"
"1","(-3275,2175)","0","mstr_standard","I230";
;
CDS_LIB"mstr_standard"
BODY_TYPE"PLUMBING"
HDL_TAP"TRUE";
"B \NAC \NWC"3;
"S \NAC"
BN"3"105;
%"TAP"
"1","(-3275,2125)","0","mstr_standard","I231";
;
CDS_LIB"mstr_standard"
BODY_TYPE"PLUMBING"
HDL_TAP"TRUE";
"B \NAC \NWC"3;
"S \NAC"
BN"4"104;
%"TAP"
"1","(-3275,2075)","0","mstr_standard","I232";
;
CDS_LIB"mstr_standard"
BODY_TYPE"PLUMBING"
HDL_TAP"TRUE";
"B \NAC \NWC"3;
"S \NAC"
BN"5"102;
%"TAP"
"1","(-3275,2025)","0","mstr_standard","I234";
;
CDS_LIB"mstr_standard"
BODY_TYPE"PLUMBING"
HDL_TAP"TRUE";
"B \NAC \NWC"3;
"S \NAC"
BN"6"87;
%"TAP"
"1","(-3275,1975)","0","mstr_standard","I235";
;
CDS_LIB"mstr_standard"
BODY_TYPE"PLUMBING"
HDL_TAP"TRUE";
"B \NAC \NWC"3;
"S \NAC"
BN"7"85;
%"TAP"
"1","(-3275,1875)","0","mstr_standard","I236";
;
CDS_LIB"mstr_standard"
BODY_TYPE"PLUMBING"
HDL_TAP"TRUE";
"B \NAC \NWC"4;
"S \NAC"
BN"0"88;
%"TAP"
"1","(-3275,1825)","0","mstr_standard","I237";
;
CDS_LIB"mstr_standard"
BODY_TYPE"PLUMBING"
HDL_TAP"TRUE";
"B \NAC \NWC"4;
"S \NAC"
BN"1"86;
%"TAP"
"1","(-3275,1775)","0","mstr_standard","I238";
;
CDS_LIB"mstr_standard"
BODY_TYPE"PLUMBING"
HDL_TAP"TRUE";
"B \NAC \NWC"4;
"S \NAC"
BN"2"84;
%"TAP"
"1","(-3275,1675)","0","mstr_standard","I239";
;
CDS_LIB"mstr_standard"
BODY_TYPE"PLUMBING"
HDL_TAP"TRUE";
"B \NAC \NWC"4;
"S \NAC"
BN"4"82;
%"TAP"
"1","(-3275,1725)","0","mstr_standard","I240";
;
CDS_LIB"mstr_standard"
BODY_TYPE"PLUMBING"
HDL_TAP"TRUE";
"B \NAC \NWC"4;
"S \NAC"
BN"3"83;
%"TAP"
"1","(-3275,1575)","0","mstr_standard","I241";
;
CDS_LIB"mstr_standard"
BODY_TYPE"PLUMBING"
HDL_TAP"TRUE";
"B \NAC \NWC"4;
"S \NAC"
BN"6"80;
%"TAP"
"1","(-3275,1625)","0","mstr_standard","I242";
;
CDS_LIB"mstr_standard"
BODY_TYPE"PLUMBING"
HDL_TAP"TRUE";
"B \NAC \NWC"4;
"S \NAC"
BN"5"81;
%"TAP"
"1","(-3275,1525)","0","mstr_standard","I243";
;
CDS_LIB"mstr_standard"
BODY_TYPE"PLUMBING"
HDL_TAP"TRUE";
"B \NAC \NWC"4;
"S \NAC"
BN"7"79;
%"TAP"
"1","(-5700,5925)","2","mstr_standard","I244";
;
CDS_LIB"mstr_standard"
BODY_TYPE"PLUMBING"
HDL_TAP"TRUE";
"B \NAC \NWC"6;
"S \NAC"
BN"0"73;
%"TAP"
"1","(-5700,5825)","2","mstr_standard","I245";
;
CDS_LIB"mstr_standard"
BODY_TYPE"PLUMBING"
HDL_TAP"TRUE";
"B \NAC \NWC"6;
"S \NAC"
BN"1"71;
%"TAP"
"1","(-5700,5625)","2","mstr_standard","I246";
;
CDS_LIB"mstr_standard"
BODY_TYPE"PLUMBING"
HDL_TAP"TRUE";
"B \NAC \NWC"6;
"S \NAC"
BN"3"67;
%"TAP"
"1","(-5700,5725)","2","mstr_standard","I247";
;
CDS_LIB"mstr_standard"
BODY_TYPE"PLUMBING"
HDL_TAP"TRUE";
"B \NAC \NWC"6;
"S \NAC"
BN"2"69;
%"TAP"
"1","(-5900,5775)","2","mstr_standard","I248";
;
CDS_LIB"mstr_standard"
BODY_TYPE"PLUMBING"
HDL_TAP"TRUE";
"B \NAC \NWC"5;
"S \NAC"
BN"1"77;
%"TAP"
"1","(-5900,5875)","2","mstr_standard","I249";
;
CDS_LIB"mstr_standard"
BODY_TYPE"PLUMBING"
HDL_TAP"TRUE";
"B \NAC \NWC"5;
"S \NAC"
BN"0"78;
%"TAP"
"1","(-5900,5675)","2","mstr_standard","I250";
;
CDS_LIB"mstr_standard"
BODY_TYPE"PLUMBING"
HDL_TAP"TRUE";
"B \NAC \NWC"5;
"S \NAC"
BN"2"76;
%"TAP"
"1","(-5700,5525)","2","mstr_standard","I251";
;
CDS_LIB"mstr_standard"
BODY_TYPE"PLUMBING"
HDL_TAP"TRUE";
"B \NAC \NWC"6;
"S \NAC"
BN"4"66;
%"TAP"
"1","(-5700,5425)","2","mstr_standard","I252";
;
CDS_LIB"mstr_standard"
BODY_TYPE"PLUMBING"
HDL_TAP"TRUE";
"B \NAC \NWC"6;
"S \NAC"
BN"5"65;
%"TAP"
"1","(-5900,5575)","2","mstr_standard","I253";
;
CDS_LIB"mstr_standard"
BODY_TYPE"PLUMBING"
HDL_TAP"TRUE";
"B \NAC \NWC"5;
"S \NAC"
BN"3"75;
%"TAP"
"1","(-5900,5475)","2","mstr_standard","I254";
;
CDS_LIB"mstr_standard"
BODY_TYPE"PLUMBING"
HDL_TAP"TRUE";
"B \NAC \NWC"5;
"S \NAC"
BN"4"74;
%"TAP"
"1","(-5700,5225)","2","mstr_standard","I255";
;
CDS_LIB"mstr_standard"
BODY_TYPE"PLUMBING"
HDL_TAP"TRUE";
"B \NAC \NWC"6;
"S \NAC"
BN"7"63;
%"TAP"
"1","(-5700,5325)","2","mstr_standard","I256";
;
CDS_LIB"mstr_standard"
BODY_TYPE"PLUMBING"
HDL_TAP"TRUE";
"B \NAC \NWC"6;
"S \NAC"
BN"6"64;
%"TAP"
"1","(-5700,5125)","2","mstr_standard","I257";
;
CDS_LIB"mstr_standard"
BODY_TYPE"PLUMBING"
HDL_TAP"TRUE";
"B \NAC \NWC"6;
"S \NAC"
BN"8"62;
%"TAP"
"1","(-5900,5275)","2","mstr_standard","I258";
;
CDS_LIB"mstr_standard"
BODY_TYPE"PLUMBING"
HDL_TAP"TRUE";
"B \NAC \NWC"5;
"S \NAC"
BN"6"70;
%"TAP"
"1","(-5900,5375)","2","mstr_standard","I259";
;
CDS_LIB"mstr_standard"
BODY_TYPE"PLUMBING"
HDL_TAP"TRUE";
"B \NAC \NWC"5;
"S \NAC"
BN"5"72;
%"TAP"
"1","(-5900,5175)","2","mstr_standard","I260";
;
CDS_LIB"mstr_standard"
BODY_TYPE"PLUMBING"
HDL_TAP"TRUE";
"B \NAC \NWC"5;
"S \NAC"
BN"7"68;
%"TAP"
"1","(-5700,4875)","2","mstr_standard","I261";
;
CDS_LIB"mstr_standard"
BODY_TYPE"PLUMBING"
HDL_TAP"TRUE";
"B \NAC \NWC"7;
"S \NAC"
BN"0"51;
%"TAP"
"1","(-5700,5025)","2","mstr_standard","I262";
;
CDS_LIB"mstr_standard"
BODY_TYPE"PLUMBING"
HDL_TAP"TRUE";
"B \NAC \NWC"6;
"S \NAC"
BN"9"44;
%"TAP"
"1","(-5900,5075)","2","mstr_standard","I263";
;
CDS_LIB"mstr_standard"
BODY_TYPE"PLUMBING"
HDL_TAP"TRUE";
"B \NAC \NWC"5;
"S \NAC"
BN"8"55;
%"TAP"
"1","(-5900,4975)","2","mstr_standard","I264";
;
CDS_LIB"mstr_standard"
BODY_TYPE"PLUMBING"
HDL_TAP"TRUE";
"B \NAC \NWC"5;
"S \NAC"
BN"9"53;
%"TAP"
"1","(-5700,4775)","2","mstr_standard","I265";
;
CDS_LIB"mstr_standard"
BODY_TYPE"PLUMBING"
HDL_TAP"TRUE";
"B \NAC \NWC"7;
"S \NAC"
BN"1"49;
%"TAP"
"1","(-5700,4675)","2","mstr_standard","I266";
;
CDS_LIB"mstr_standard"
BODY_TYPE"PLUMBING"
HDL_TAP"TRUE";
"B \NAC \NWC"7;
"S \NAC"
BN"2"47;
%"TAP"
"1","(-5900,4825)","2","mstr_standard","I267";
;
CDS_LIB"mstr_standard"
BODY_TYPE"PLUMBING"
HDL_TAP"TRUE";
"B \NAC \NWC"8;
"S \NAC"
BN"0"58;
%"TAP"
"1","(-5900,4725)","2","mstr_standard","I268";
;
CDS_LIB"mstr_standard"
BODY_TYPE"PLUMBING"
HDL_TAP"TRUE";
"B \NAC \NWC"8;
"S \NAC"
BN"1"57;
%"TAP"
"1","(-5900,4625)","2","mstr_standard","I269";
;
CDS_LIB"mstr_standard"
BODY_TYPE"PLUMBING"
HDL_TAP"TRUE";
"B \NAC \NWC"8;
"S \NAC"
BN"2"56;
%"TAP"
"1","(-5700,4475)","2","mstr_standard","I270";
;
CDS_LIB"mstr_standard"
BODY_TYPE"PLUMBING"
HDL_TAP"TRUE";
"B \NAC \NWC"7;
"S \NAC"
BN"4"43;
%"TAP"
"1","(-5700,4575)","2","mstr_standard","I271";
;
CDS_LIB"mstr_standard"
BODY_TYPE"PLUMBING"
HDL_TAP"TRUE";
"B \NAC \NWC"7;
"S \NAC"
BN"3"45;
%"TAP"
"1","(-5700,4375)","2","mstr_standard","I272";
;
CDS_LIB"mstr_standard"
BODY_TYPE"PLUMBING"
HDL_TAP"TRUE";
"B \NAC \NWC"7;
"S \NAC"
BN"5"61;
%"TAP"
"1","(-5900,4525)","2","mstr_standard","I273";
;
CDS_LIB"mstr_standard"
BODY_TYPE"PLUMBING"
HDL_TAP"TRUE";
"B \NAC \NWC"8;
"S \NAC"
BN"3"54;
%"TAP"
"1","(-5900,4425)","2","mstr_standard","I274";
;
CDS_LIB"mstr_standard"
BODY_TYPE"PLUMBING"
HDL_TAP"TRUE";
"B \NAC \NWC"8;
"S \NAC"
BN"4"52;
%"TAP"
"1","(-5700,4275)","2","mstr_standard","I275";
;
CDS_LIB"mstr_standard"
BODY_TYPE"PLUMBING"
HDL_TAP"TRUE";
"B \NAC \NWC"7;
"S \NAC"
BN"6"60;
%"TAP"
"1","(-5700,4175)","2","mstr_standard","I276";
;
CDS_LIB"mstr_standard"
BODY_TYPE"PLUMBING"
HDL_TAP"TRUE";
"B \NAC \NWC"7;
"S \NAC"
BN"7"59;
%"TAP"
"1","(-5900,4225)","2","mstr_standard","I277";
;
CDS_LIB"mstr_standard"
BODY_TYPE"PLUMBING"
HDL_TAP"TRUE";
"B \NAC \NWC"8;
"S \NAC"
BN"6"48;
%"TAP"
"1","(-5900,4325)","2","mstr_standard","I278";
;
CDS_LIB"mstr_standard"
BODY_TYPE"PLUMBING"
HDL_TAP"TRUE";
"B \NAC \NWC"8;
"S \NAC"
BN"5"50;
%"TAP"
"1","(-5900,4125)","2","mstr_standard","I279";
;
CDS_LIB"mstr_standard"
BODY_TYPE"PLUMBING"
HDL_TAP"TRUE";
"B \NAC \NWC"8;
"S \NAC"
BN"7"46;
%"TAP"
"1","(-5700,4075)","2","mstr_standard","I284";
;
CDS_LIB"mstr_standard"
BODY_TYPE"PLUMBING"
HDL_TAP"TRUE";
"B \NAC \NWC"7;
"S \NAC"
BN"8"35;
%"TAP"
"1","(-5700,3975)","2","mstr_standard","I285";
;
CDS_LIB"mstr_standard"
BODY_TYPE"PLUMBING"
HDL_TAP"TRUE";
"B \NAC \NWC"7;
"S \NAC"
BN"9"32;
%"TAP"
"1","(-5900,4025)","2","mstr_standard","I286";
;
CDS_LIB"mstr_standard"
BODY_TYPE"PLUMBING"
HDL_TAP"TRUE";
"B \NAC \NWC"8;
"S \NAC"
BN"8"27;
%"TAP"
"1","(-5900,3925)","2","mstr_standard","I287";
;
CDS_LIB"mstr_standard"
BODY_TYPE"PLUMBING"
HDL_TAP"TRUE";
"B \NAC \NWC"8;
"S \NAC"
BN"9"42;
%"TAP"
"1","(-5900,3725)","2","mstr_standard","I288";
;
CDS_LIB"mstr_standard"
BODY_TYPE"PLUMBING"
HDL_TAP"TRUE";
"B \NAC \NWC"10;
"S \NAC"
BN"1"25;
%"TAP"
"1","(-5900,3775)","2","mstr_standard","I289";
;
CDS_LIB"mstr_standard"
BODY_TYPE"PLUMBING"
HDL_TAP"TRUE";
"B \NAC \NWC"10;
"S \NAC"
BN"0"28;
%"TAP"
"1","(-5900,3625)","2","mstr_standard","I290";
;
CDS_LIB"mstr_standard"
BODY_TYPE"PLUMBING"
HDL_TAP"TRUE";
"B \NAC \NWC"10;
"S \NAC"
BN"3"38;
%"TAP"
"1","(-5900,3675)","2","mstr_standard","I291";
;
CDS_LIB"mstr_standard"
BODY_TYPE"PLUMBING"
HDL_TAP"TRUE";
"B \NAC \NWC"10;
"S \NAC"
BN"2"40;
%"TAP"
"1","(-5900,3475)","2","mstr_standard","I292";
;
CDS_LIB"mstr_standard"
BODY_TYPE"PLUMBING"
HDL_TAP"TRUE";
"B \NAC \NWC"10;
"S \NAC"
BN"6"30;
%"TAP"
"1","(-5900,3525)","2","mstr_standard","I293";
;
CDS_LIB"mstr_standard"
BODY_TYPE"PLUMBING"
HDL_TAP"TRUE";
"B \NAC \NWC"10;
"S \NAC"
BN"5"33;
%"TAP"
"1","(-5900,3575)","2","mstr_standard","I294";
;
CDS_LIB"mstr_standard"
BODY_TYPE"PLUMBING"
HDL_TAP"TRUE";
"B \NAC \NWC"10;
"S \NAC"
BN"4"36;
%"TAP"
"1","(-5900,3375)","2","mstr_standard","I295";
;
CDS_LIB"mstr_standard"
BODY_TYPE"PLUMBING"
HDL_TAP"TRUE";
"B \NAC \NWC"9;
"S \NAC"
BN"0"26;
%"TAP"
"1","(-5900,3325)","2","mstr_standard","I296";
;
CDS_LIB"mstr_standard"
BODY_TYPE"PLUMBING"
HDL_TAP"TRUE";
"B \NAC \NWC"9;
"S \NAC"
BN"1"41;
%"TAP"
"1","(-5900,3225)","2","mstr_standard","I297";
;
CDS_LIB"mstr_standard"
BODY_TYPE"PLUMBING"
HDL_TAP"TRUE";
"B \NAC \NWC"9;
"S \NAC"
BN"3"37;
%"TAP"
"1","(-5900,3275)","2","mstr_standard","I298";
;
CDS_LIB"mstr_standard"
BODY_TYPE"PLUMBING"
HDL_TAP"TRUE";
"B \NAC \NWC"9;
"S \NAC"
BN"2"39;
%"TAP"
"1","(-5900,3075)","2","mstr_standard","I299";
;
CDS_LIB"mstr_standard"
BODY_TYPE"PLUMBING"
HDL_TAP"TRUE";
"B \NAC \NWC"9;
"S \NAC"
BN"6"29;
%"TAP"
"1","(-5900,3125)","2","mstr_standard","I300";
;
CDS_LIB"mstr_standard"
BODY_TYPE"PLUMBING"
HDL_TAP"TRUE";
"B \NAC \NWC"9;
"S \NAC"
BN"5"31;
%"TAP"
"1","(-5900,3175)","2","mstr_standard","I301";
;
CDS_LIB"mstr_standard"
BODY_TYPE"PLUMBING"
HDL_TAP"TRUE";
"B \NAC \NWC"9;
"S \NAC"
BN"4"34;
%"Q_RES"
"1","(-6575,2075)","0","pure_quanta","I313";
;
LOCATION"R511"
$SEC"1"
CDS_SEC"1"
PACK_TYPE"0402LF"
TOLERANCE"1%"
VALUE"15"
MATERIAL"CHIP"
WATTAGE"1/16W"
CDS_LIB"pure_quanta"
PART_NUMBER"CS01502FB03";
"B"
$PN"2"12;
"A"
$PN"1"11;
END.
